# BASEBOARD_FAB2 (Tioga Pass) — schematic netlist excerpt (pin names and nets, part order shuffled) for the footprints in the layout excerpt that follows; sources: Cadence DE-HDL packaged netlist, KiCad conversion of Wiwynn_Tioga_Pass_MB.brd

C22W3  SC22U16V5MX-4-GP  20%  pkg SMD-BCG5  page 225 : \1\ = VR_FET_SW_P12V_STBY_PVDDQ_GHJ ; \2\ = GND
R6M9  RES  4.75K 1% CHIP  pkg 0402  page 192 : A = PVPP_KLM ; B = RST_CD_CPU1_POR_N
R1U47  RES  5.11K 1% CHIP  pkg 0402  page 169 : A = P5V_STBY ; B = A_P5V_STBY_SCALED

(kicad_pcb
	(version 20260206)
	(generator "pcbnew")
	(generator_version "10.0")
	(general
		(thickness 1.6)
		(legacy_teardrops no)
	)
	(paper "A4")
	(title_block
		(title "Wiwynn_Tioga_Pass_MB.brd")
		(comment 1 "Tioga Pass / footprints 3712-3714 of 4770")
	)
	(layers
		(0 "F.Cu" signal "TOP")
		(4 "In1.Cu" signal "L2GND")
		(6 "In2.Cu" signal "L3")
		(8 "In3.Cu" signal "L4GND")
		(10 "In4.Cu" signal "L5")
		(12 "In5.Cu" signal "L6GND")
		(14 "In6.Cu" signal "L7VCC")
		(16 "In7.Cu" signal "L8VCC")
		(18 "In8.Cu" signal "L9GND")
		(20 "In9.Cu" signal "L10")
		(22 "In10.Cu" signal "L11GND")
		(24 "In11.Cu" signal "L12")
		(26 "In12.Cu" signal "L13GND")
		(2 "B.Cu" signal "BOTTOM")
		(9 "F.Adhes" user "F.Adhesive")
		(11 "B.Adhes" user "B.Adhesive")
		(13 "F.Paste" user "Package Geometry/Pastemask Top")
		(15 "B.Paste" user "Package Geometry/Pastemask Bottom")
		(5 "F.SilkS" user "Ref Des/Silkscreen Top")
		(7 "B.SilkS" user "Ref Des/Silkscreen Bottom")
		(1 "F.Mask" user "Board Geometry/Soldermask Top")
		(3 "B.Mask" user "Board Geometry/Soldermask Bottom")
		(17 "Dwgs.User" user "User.Drawings")
		(19 "Cmts.User" user "User.Comments")
		(21 "Eco1.User" user "User.Eco1")
		(23 "Eco2.User" user "User.Eco2")
		(25 "Edge.Cuts" user "Board Geometry/Outline")
		(27 "Margin" user)
		(31 "F.CrtYd" user "Package Geometry/Place Bound Top")
		(29 "B.CrtYd" user "Package Geometry/Place Bound Bottom")
		(35 "F.Fab" user "Ref Des/Assembly Top")
		(33 "B.Fab" user "Ref Des/Assembly Bottom")
	)
	(footprint ""
		(layer "B.Cu")
		(at -3.0861 -14.08684 -90)
		(property "Reference" "C22W3"
			(at 0 0 90)
			(layer "B.SilkS")
			(hide yes)
			(effects
				(font
					(size 1.27 1.27)
				)
				(justify mirror)
			)
		)
		(property "Value" "*"
			(at 0.0762 -6.2357 270)
			(unlocked yes)
			(layer "B.Fab")
			(hide yes)
			(effects
				(font
					(size 1.27 1.016)
					(thickness 0.1524)
				)
				(justify mirror)
			)
		)
		(property "Device Type" "SC22U16V5MX-4-GP_SMD-BCG5-SC22A"
			(at 0.0762 -8.2677 270)
			(unlocked yes)
			(layer "B.Fab")
			(hide yes)
			(effects
				(font
					(size 1.27 1.016)
					(thickness 0.1524)
				)
				(justify mirror)
			)
		)
		(duplicate_pad_numbers_are_jumpers no)
		(fp_line
			(start -0.635 0)
			(end 0.635 0)
			(stroke
				(width 0.508)
				(type default)
			)
			(layer "B.SilkS")
		)
		(fp_rect
			(start 0.9652 1.778)
			(end -0.9652 -1.778)
			(stroke
				(width 0)
				(type default)
			)
			(fill no)
			(layer "B.CrtYd")
		)
		(fp_poly
			(pts
				(xy 0.9652 -1.778) (xy -0.9652 -1.778) (xy -0.9652 1.778) (xy 0.9652 1.778)
			)
			(stroke
				(width 0)
				(type default)
			)
			(fill no)
			(layer "B.Fab")
		)
		(pad "1" smd rect
			(at 0 -0.9652 90)
			(size 1.397 1.143)
			(layers "B.Cu" "B.Mask" "B.Paste")
			(net "VR_FET_SW_P12V_STBY_PVDDQ_GHJ")
		)
		(pad "2" smd rect
			(at 0 0.9652 90)
			(size 1.397 1.143)
			(layers "B.Cu" "B.Mask" "B.Paste")
			(net "GND")
		)
	)
	(footprint ""
		(layer "B.Cu")
		(at 399.737834 -25.690068 90)
		(property "Reference" "R1U47"
			(at 0 0 90)
			(layer "B.SilkS")
			(hide yes)
			(effects
				(font
					(size 1.27 1.27)
				)
				(justify mirror)
			)
		)
		(property "Value" ""
			(at 0 0 90)
			(layer "B.Fab")
			(effects
				(font
					(size 1.27 1.27)
				)
				(justify mirror)
			)
		)
		(duplicate_pad_numbers_are_jumpers no)
		(fp_poly
			(pts
				(xy 0.2794 -0.1016) (xy -0.2794 -0.1016) (xy -0.2794 0.9906) (xy 0.2794 0.9906)
			)
			(stroke
				(width 0)
				(type default)
			)
			(fill no)
			(layer "B.CrtYd")
		)
		(fp_line
			(start 0.2794 -0.1016)
			(end 0.2794 0.9906)
			(stroke
				(width 0.1)
				(type default)
			)
			(layer "B.Fab")
		)
		(fp_line
			(start -0.2794 -0.1016)
			(end 0.2794 -0.1016)
			(stroke
				(width 0.1)
				(type default)
			)
			(layer "B.Fab")
		)
		(fp_line
			(start 0.2794 0.9906)
			(end -0.2794 0.9906)
			(stroke
				(width 0.1)
				(type default)
			)
			(layer "B.Fab")
		)
		(fp_line
			(start -0.2794 0.9906)
			(end -0.2794 -0.1016)
			(stroke
				(width 0.1)
				(type default)
			)
			(layer "B.Fab")
		)
		(pad "1" smd rect
			(at 0 0 270)
			(size 0.508 0.508)
			(layers "B.Cu" "B.Mask" "B.Paste")
			(net "P5V_STBY")
		)
		(pad "2" smd rect
			(at 0 0.889 270)
			(size 0.508 0.508)
			(layers "B.Cu" "B.Mask" "B.Paste")
			(net "A_P5V_STBY_SCALED")
		)
		(zone
			(layer "B.Cu")
			(hatch none 0.5)
			(connect_pads
				(clearance 0)
			)
			(min_thickness 0.25)
			(keepout
				(tracks allowed)
				(vias not_allowed)
				(pads allowed)
				(copperpour not_allowed)
				(footprints allowed)
			)
			(placement
				(enabled no)
				(sheetname "")
			)
			(fill
				(thermal_gap 0.5)
				(thermal_bridge_width 0.5)
				(island_removal_mode 0)
			)
			(polygon
				(pts
					(xy 399.991834 -25.944068) (xy 399.991834 -25.436068) (xy 400.372834 -25.436068) (xy 400.372834 -25.944068)
				)
			)
		)
		(zone
			(layer "B.Cu")
			(hatch none 0.5)
			(connect_pads
				(clearance 0)
			)
			(min_thickness 0.25)
			(keepout
				(tracks not_allowed)
				(vias allowed)
				(pads allowed)
				(copperpour not_allowed)
				(footprints allowed)
			)
			(placement
				(enabled no)
				(sheetname "")
			)
			(fill
				(thermal_gap 0.5)
				(thermal_bridge_width 0.5)
				(island_removal_mode 0)
			)
			(polygon
				(pts
					(xy 400.372834 -25.944068) (xy 400.372834 -25.436068) (xy 399.991834 -25.436068) (xy 399.991834 -25.944068)
				)
			)
		)
	)
	(footprint ""
		(layer "B.Cu")
		(at 168.148 -123.19 180)
		(property "Reference" "R6M9"
			(at 0 0 0)
			(layer "B.SilkS")
			(hide yes)
			(effects
				(font
					(size 1.27 1.27)
				)
				(justify mirror)
			)
		)
		(property "Value" ""
			(at 0 0 0)
			(layer "B.Fab")
			(effects
				(font
					(size 1.27 1.27)
				)
				(justify mirror)
			)
		)
		(duplicate_pad_numbers_are_jumpers no)
		(fp_poly
			(pts
				(xy 0.2794 -0.1016) (xy -0.2794 -0.1016) (xy -0.2794 0.9906) (xy 0.2794 0.9906)
			)
			(stroke
				(width 0)
				(type default)
			)
			(fill no)
			(layer "B.CrtYd")
		)
		(fp_line
			(start 0.2794 0.9906)
			(end -0.2794 0.9906)
			(stroke
				(width 0.1)
				(type default)
			)
			(layer "B.Fab")
		)
		(fp_line
			(start 0.2794 -0.1016)
			(end 0.2794 0.9906)
			(stroke
				(width 0.1)
				(type default)
			)
			(layer "B.Fab")
		)
		(fp_line
			(start -0.2794 0.9906)
			(end -0.2794 -0.1016)
			(stroke
				(width 0.1)
				(type default)
			)
			(layer "B.Fab")
		)
		(fp_line
			(start -0.2794 -0.1016)
			(end 0.2794 -0.1016)
			(stroke
				(width 0.1)
				(type default)
			)
			(layer "B.Fab")
		)
		(pad "1" smd rect
			(at 0 0)
			(size 0.508 0.508)
			(layers "B.Cu" "B.Mask" "B.Paste")
			(net "PVPP_KLM")
		)
		(pad "2" smd rect
			(at 0 0.889)
			(size 0.508 0.508)
			(layers "B.Cu" "B.Mask" "B.Paste")
			(net "RST_CD_CPU1_POR_N")
		)
		(zone
			(layer "B.Cu")
			(hatch none 0.5)
			(connect_pads
				(clearance 0)
			)
			(min_thickness 0.25)
			(keepout
				(tracks not_allowed)
				(vias allowed)
				(pads allowed)
				(copperpour not_allowed)
				(footprints allowed)
			)
			(placement
				(enabled no)
				(sheetname "")
			)
			(fill
				(thermal_gap 0.5)
				(thermal_bridge_width 0.5)
				(island_removal_mode 0)
			)
			(polygon
				(pts
					(xy 167.894 -123.825) (xy 168.402 -123.825) (xy 168.402 -123.444) (xy 167.894 -123.444)
				)
			)
		)
		(zone
			(layer "B.Cu")
			(hatch none 0.5)
			(connect_pads
				(clearance 0)
			)
			(min_thickness 0.25)
			(keepout
				(tracks allowed)
				(vias not_allowed)
				(pads allowed)
				(copperpour not_allowed)
				(footprints allowed)
			)
			(placement
				(enabled no)
				(sheetname "")
			)
			(fill
				(thermal_gap 0.5)
				(thermal_bridge_width 0.5)
				(island_removal_mode 0)
			)
			(polygon
				(pts
					(xy 167.894 -123.444) (xy 168.402 -123.444) (xy 168.402 -123.825) (xy 167.894 -123.825)
				)
			)
		)
	)
)
